(kicad_pcb
	(version 20260206)
	(generator "pcbnew")
	(generator_version "10.0")
	(general
		(thickness 1.6)
		(legacy_teardrops no)
	)
	(paper "A4")
	(title_block
		(title "baseboard — 13948-1b.1110WZS1818.brd")
		(comment 1 "Honey Badger (Wiwynn) / footprints 977-985 of 2523")
	)
	(layers
		(0 "F.Cu" signal "TOP")
		(4 "In1.Cu" signal "L2GND")
		(6 "In2.Cu" signal "L3")
		(8 "In3.Cu" signal "L4VCC")
		(10 "In4.Cu" signal "L5VCC")
		(12 "In5.Cu" signal "L6")
		(14 "In6.Cu" signal "L7GND")
		(2 "B.Cu" signal "BOTTOM")
		(9 "F.Adhes" user "F.Adhesive")
		(11 "B.Adhes" user "B.Adhesive")
		(13 "F.Paste" user "Package Geometry/Pastemask Top")
		(15 "B.Paste" user "Package Geometry/Pastemask Bottom")
		(5 "F.SilkS" user "Ref Des/Silkscreen Top")
		(7 "B.SilkS" user "Ref Des/Silkscreen Bottom")
		(1 "F.Mask" user "Board Geometry/Soldermask Top")
		(3 "B.Mask" user "Board Geometry/Soldermask Bottom")
		(17 "Dwgs.User" user "User.Drawings")
		(19 "Cmts.User" user "User.Comments")
		(21 "Eco1.User" user "User.Eco1")
		(23 "Eco2.User" user "User.Eco2")
		(25 "Edge.Cuts" user "Board Geometry/Outline")
		(27 "Margin" user)
		(31 "F.CrtYd" user "Package Geometry/Place Bound Top")
		(29 "B.CrtYd" user "Package Geometry/Place Bound Bottom")
		(35 "F.Fab" user "Ref Des/Assembly Top")
		(33 "B.Fab" user "Ref Des/Assembly Bottom")
	)
	(footprint ""
		(layer "F.Cu")
		(at 276.733 -104.267)
		(property "Reference" "PR177"
			(at 0 0 0)
			(layer "F.SilkS")
			(hide yes)
			(effects
				(font
					(size 1.27 1.27)
				)
			)
		)
		(property "Value" "1KR2F-3-GP"
			(at 0.064008 -3.993896 0)
			(unlocked yes)
			(layer "F.Fab")
			(hide yes)
			(effects
				(font
					(size 1.016 1.016)
					(thickness 0.1524)
				)
			)
		)
		(property "Device Type" "R402H16"
			(at 0.064008 -5.517896 0)
			(unlocked yes)
			(layer "F.Fab")
			(hide yes)
			(effects
				(font
					(size 1.016 1.016)
					(thickness 0.1524)
				)
			)
		)
		(duplicate_pad_numbers_are_jumpers no)
		(fp_line
			(start -0.508 -0.9398)
			(end -0.508 0.9398)
			(stroke
				(width 0.1524)
				(type default)
			)
			(layer "F.SilkS")
		)
		(fp_line
			(start 0.508 -0.9398)
			(end -0.508 -0.9398)
			(stroke
				(width 0.1524)
				(type default)
			)
			(layer "F.SilkS")
		)
		(fp_rect
			(start -0.508 0.9398)
			(end 0.508 -0.9398)
			(stroke
				(width 0)
				(type default)
			)
			(fill no)
			(layer "F.CrtYd")
		)
		(fp_rect
			(start -0.508 0.9398)
			(end 0.508 -0.9398)
			(stroke
				(width 0)
				(type default)
			)
			(fill no)
			(layer "F.Fab")
		)
		(pad "1" smd custom
			(at 0 -0.4445)
			(size 0.1397 0.1397)
			(layers "F.Cu" "F.Mask" "F.Paste")
			(net "P1V8_C")
			(options
				(clearance outline)
				(anchor circle)
			)
			(primitives
				(gr_poly
					(pts
						(arc
							(start -0.1778 -0.2794)
							(mid -0.249642 -0.249642)
							(end -0.2794 -0.1778)
						)
						(arc
							(start -0.2794 0.1778)
							(mid -0.249642 0.249642)
							(end -0.1778 0.2794)
						)
						(arc
							(start 0.1778 0.2794)
							(mid 0.249642 0.249642)
							(end 0.2794 0.1778)
						)
						(arc
							(start 0.2794 -0.1778)
							(mid 0.249642 -0.249642)
							(end 0.1778 -0.2794)
						)
					)
					(width 0)
					(fill yes)
				)
			)
		)
		(pad "2" smd custom
			(at 0 0.4445)
			(size 0.1397 0.1397)
			(layers "F.Cu" "F.Mask" "F.Paste")
			(net "GND")
			(options
				(clearance outline)
				(anchor circle)
			)
			(primitives
				(gr_poly
					(pts
						(arc
							(start -0.1778 -0.2794)
							(mid -0.249642 -0.249642)
							(end -0.2794 -0.1778)
						)
						(arc
							(start -0.2794 0.1778)
							(mid -0.249642 0.249642)
							(end -0.1778 0.2794)
						)
						(arc
							(start 0.1778 0.2794)
							(mid 0.249642 0.249642)
							(end 0.2794 0.1778)
						)
						(arc
							(start 0.2794 -0.1778)
							(mid 0.249642 -0.249642)
							(end 0.1778 -0.2794)
						)
					)
					(width 0)
					(fill yes)
				)
			)
		)
	)
	(footprint ""
		(layer "F.Cu")
		(at 279.6794 -183.642)
		(property "Reference" "TP150"
			(at 0 0 0)
			(layer "F.SilkS")
			(hide yes)
			(effects
				(font
					(size 1.27 1.27)
				)
			)
		)
		(property "Value" "TPAD28"
			(at 0.0127 -1.8034 0)
			(unlocked yes)
			(layer "F.Fab")
			(hide yes)
			(effects
				(font
					(size 1.016 1.016)
					(thickness 0.1524)
				)
			)
		)
		(property "Device Type" "TPAD28"
			(at 0.0127 -3.3274 0)
			(unlocked yes)
			(layer "F.Fab")
			(hide yes)
			(effects
				(font
					(size 1.016 1.016)
					(thickness 0.1524)
				)
			)
		)
		(duplicate_pad_numbers_are_jumpers no)
		(fp_poly
			(pts
				(arc
					(start 0.3556 0)
					(mid -0.3556 0)
					(end 0.3556 0)
				)
			)
			(stroke
				(width 0)
				(type default)
			)
			(fill no)
			(layer "F.CrtYd")
		)
		(fp_poly
			(pts
				(arc
					(start 0.6096 0)
					(mid -0.6096 0)
					(end 0.6096 0)
				)
			)
			(stroke
				(width 0)
				(type default)
			)
			(fill no)
			(layer "F.Fab")
		)
		(pad "1" smd circle
			(at 0 0)
			(size 0.7112 0.7112)
			(layers "F.Cu" "F.Mask" "F.Paste")
			(net "TP_BMC_GPIOR5")
		)
	)
	(footprint ""
		(layer "F.Cu")
		(at 97.282 -239.522 90)
		(property "Reference" "SC434"
			(at 0 0 90)
			(layer "F.SilkS")
			(hide yes)
			(effects
				(font
					(size 1.27 1.27)
				)
			)
		)
		(property "Value" "SC1U10V3KX-4GP-U"
			(at 0 -2.8194 90)
			(unlocked yes)
			(layer "F.Fab")
			(hide yes)
			(effects
				(font
					(size 1.016 1.016)
					(thickness 0.1524)
				)
			)
		)
		(property "Device Type" "C603H36"
			(at 0 -4.3434 90)
			(unlocked yes)
			(layer "F.Fab")
			(hide yes)
			(effects
				(font
					(size 1.016 1.016)
					(thickness 0.1524)
				)
			)
		)
		(duplicate_pad_numbers_are_jumpers no)
		(fp_line
			(start 0.508 0)
			(end -0.508 0)
			(stroke
				(width 0.2032)
				(type default)
			)
			(layer "F.SilkS")
		)
		(fp_rect
			(start -0.5842 1.3335)
			(end 0.5842 -1.3335)
			(stroke
				(width 0)
				(type default)
			)
			(fill no)
			(layer "F.CrtYd")
		)
		(fp_rect
			(start -0.5842 1.3335)
			(end 0.5842 -1.3335)
			(stroke
				(width 0)
				(type default)
			)
			(fill no)
			(layer "F.Fab")
		)
		(pad "1" smd custom
			(at 0 -0.762 90)
			(size 0.2159 0.2159)
			(layers "F.Cu" "F.Mask" "F.Paste")
			(net "GND")
			(options
				(clearance outline)
				(anchor circle)
			)
			(primitives
				(gr_poly
					(pts
						(arc
							(start -0.3302 -0.4318)
							(mid -0.402042 -0.402042)
							(end -0.4318 -0.3302)
						)
						(arc
							(start -0.4318 0.3302)
							(mid -0.402042 0.402042)
							(end -0.3302 0.4318)
						)
						(arc
							(start 0.3302 0.4318)
							(mid 0.402042 0.402042)
							(end 0.4318 0.3302)
						)
						(arc
							(start 0.4318 -0.3302)
							(mid 0.402042 -0.402042)
							(end 0.3302 -0.4318)
						)
					)
					(width 0)
					(fill yes)
				)
			)
		)
		(pad "2" smd custom
			(at 0 0.762 90)
			(size 0.2159 0.2159)
			(layers "F.Cu" "F.Mask" "F.Paste")
			(net "P3V3_STBY")
			(options
				(clearance outline)
				(anchor circle)
			)
			(primitives
				(gr_poly
					(pts
						(arc
							(start -0.3302 -0.4318)
							(mid -0.402042 -0.402042)
							(end -0.4318 -0.3302)
						)
						(arc
							(start -0.4318 0.3302)
							(mid -0.402042 0.402042)
							(end -0.3302 0.4318)
						)
						(arc
							(start 0.3302 0.4318)
							(mid 0.402042 0.402042)
							(end 0.4318 0.3302)
						)
						(arc
							(start 0.4318 -0.3302)
							(mid 0.402042 -0.402042)
							(end 0.3302 -0.4318)
						)
					)
					(width 0)
					(fill yes)
				)
			)
		)
	)
	(footprint ""
		(layer "F.Cu")
		(at 94.914212 -249.936)
		(property "Reference" "R149"
			(at 0 0 0)
			(layer "F.SilkS")
			(hide yes)
			(effects
				(font
					(size 1.27 1.27)
				)
			)
		)
		(property "Value" "0R2J-2-GP"
			(at 0.064008 -3.993896 0)
			(unlocked yes)
			(layer "F.Fab")
			(hide yes)
			(effects
				(font
					(size 1.016 1.016)
					(thickness 0.1524)
				)
			)
		)
		(property "Device Type" "R402H16"
			(at 0.064008 -5.517896 0)
			(unlocked yes)
			(layer "F.Fab")
			(hide yes)
			(effects
				(font
					(size 1.016 1.016)
					(thickness 0.1524)
				)
			)
		)
		(duplicate_pad_numbers_are_jumpers no)
		(fp_line
			(start -0.508 -0.9398)
			(end -0.508 0.9398)
			(stroke
				(width 0.1524)
				(type default)
			)
			(layer "F.SilkS")
		)
		(fp_line
			(start 0.508 -0.9398)
			(end -0.508 -0.9398)
			(stroke
				(width 0.1524)
				(type default)
			)
			(layer "F.SilkS")
		)
		(fp_rect
			(start -0.508 0.9398)
			(end 0.508 -0.9398)
			(stroke
				(width 0)
				(type default)
			)
			(fill no)
			(layer "F.CrtYd")
		)
		(fp_rect
			(start -0.508 0.9398)
			(end 0.508 -0.9398)
			(stroke
				(width 0)
				(type default)
			)
			(fill no)
			(layer "F.Fab")
		)
		(pad "1" smd custom
			(at 0 -0.4445)
			(size 0.1397 0.1397)
			(layers "F.Cu" "F.Mask" "F.Paste")
			(net "HB_INPUT")
			(options
				(clearance outline)
				(anchor circle)
			)
			(primitives
				(gr_poly
					(pts
						(arc
							(start -0.1778 -0.2794)
							(mid -0.249642 -0.249642)
							(end -0.2794 -0.1778)
						)
						(arc
							(start -0.2794 0.1778)
							(mid -0.249642 0.249642)
							(end -0.1778 0.2794)
						)
						(arc
							(start 0.1778 0.2794)
							(mid 0.249642 0.249642)
							(end 0.2794 0.1778)
						)
						(arc
							(start 0.2794 -0.1778)
							(mid 0.249642 -0.249642)
							(end 0.1778 -0.2794)
						)
					)
					(width 0)
					(fill yes)
				)
			)
		)
		(pad "2" smd custom
			(at 0 0.4445)
			(size 0.1397 0.1397)
			(layers "F.Cu" "F.Mask" "F.Paste")
			(net "HB_B_SIDE_IN")
			(options
				(clearance outline)
				(anchor circle)
			)
			(primitives
				(gr_poly
					(pts
						(arc
							(start -0.1778 -0.2794)
							(mid -0.249642 -0.249642)
							(end -0.2794 -0.1778)
						)
						(arc
							(start -0.2794 0.1778)
							(mid -0.249642 0.249642)
							(end -0.1778 0.2794)
						)
						(arc
							(start 0.1778 0.2794)
							(mid 0.249642 0.249642)
							(end 0.2794 0.1778)
						)
						(arc
							(start 0.2794 -0.1778)
							(mid 0.249642 -0.249642)
							(end 0.1778 -0.2794)
						)
					)
					(width 0)
					(fill yes)
				)
			)
		)
	)
	(footprint ""
		(layer "F.Cu")
		(at 68.326 -231.902 180)
		(property "Reference" "C7279"
			(at 0 0 180)
			(layer "F.SilkS")
			(hide yes)
			(effects
				(font
					(size 1.27 1.27)
				)
			)
		)
		(property "Value" "SCD033U50V3KX-1GP"
			(at 0 -2.8194 180)
			(unlocked yes)
			(layer "F.Fab")
			(hide yes)
			(effects
				(font
					(size 1.016 1.016)
					(thickness 0.1524)
				)
			)
		)
		(property "Device Type" "C603H36"
			(at 0 -4.3434 180)
			(unlocked yes)
			(layer "F.Fab")
			(hide yes)
			(effects
				(font
					(size 1.016 1.016)
					(thickness 0.1524)
				)
			)
		)
		(duplicate_pad_numbers_are_jumpers no)
		(fp_line
			(start 0.508 0)
			(end -0.508 0)
			(stroke
				(width 0.2032)
				(type default)
			)
			(layer "F.SilkS")
		)
		(fp_rect
			(start -0.5842 1.3335)
			(end 0.5842 -1.3335)
			(stroke
				(width 0)
				(type default)
			)
			(fill no)
			(layer "F.CrtYd")
		)
		(fp_rect
			(start -0.5842 1.3335)
			(end 0.5842 -1.3335)
			(stroke
				(width 0)
				(type default)
			)
			(fill no)
			(layer "F.Fab")
		)
		(pad "1" smd custom
			(at 0 -0.762 180)
			(size 0.2159 0.2159)
			(layers "F.Cu" "F.Mask" "F.Paste")
			(net "MB0_CM_GATE_R")
			(options
				(clearance outline)
				(anchor circle)
			)
			(primitives
				(gr_poly
					(pts
						(arc
							(start -0.3302 -0.4318)
							(mid -0.402042 -0.402042)
							(end -0.4318 -0.3302)
						)
						(arc
							(start -0.4318 0.3302)
							(mid -0.402042 0.402042)
							(end -0.3302 0.4318)
						)
						(arc
							(start 0.3302 0.4318)
							(mid 0.402042 0.402042)
							(end 0.4318 0.3302)
						)
						(arc
							(start 0.4318 -0.3302)
							(mid 0.402042 -0.402042)
							(end 0.3302 -0.4318)
						)
					)
					(width 0)
					(fill yes)
				)
			)
		)
		(pad "2" smd custom
			(at 0 0.762 180)
			(size 0.2159 0.2159)
			(layers "F.Cu" "F.Mask" "F.Paste")
			(net "GND")
			(options
				(clearance outline)
				(anchor circle)
			)
			(primitives
				(gr_poly
					(pts
						(arc
							(start -0.3302 -0.4318)
							(mid -0.402042 -0.402042)
							(end -0.4318 -0.3302)
						)
						(arc
							(start -0.4318 0.3302)
							(mid -0.402042 0.402042)
							(end -0.3302 0.4318)
						)
						(arc
							(start 0.3302 0.4318)
							(mid 0.402042 0.402042)
							(end 0.4318 0.3302)
						)
						(arc
							(start 0.4318 -0.3302)
							(mid 0.402042 -0.402042)
							(end 0.3302 -0.4318)
						)
					)
					(width 0)
					(fill yes)
				)
			)
		)
	)
	(footprint ""
		(layer "F.Cu")
		(at 152.247092 -102.518464 -90)
		(property "Reference" "SL20"
			(at 0 0 270)
			(layer "F.SilkS")
			(hide yes)
			(effects
				(font
					(size 1.27 1.27)
				)
			)
		)
		(property "Value" "MPZ2012S300AT-GP"
			(at 0 -4.2418 270)
			(unlocked yes)
			(layer "F.Fab")
			(hide yes)
			(effects
				(font
					(size 1.016 1.016)
					(thickness 0.1524)
				)
			)
		)
		(property "Device Type" "L805H42"
			(at 0 -5.7912 270)
			(unlocked yes)
			(layer "F.Fab")
			(hide yes)
			(effects
				(font
					(size 1.016 1.016)
					(thickness 0.1524)
				)
			)
		)
		(duplicate_pad_numbers_are_jumpers no)
		(fp_line
			(start -0.889 1.7018)
			(end -0.889 -1.7018)
			(stroke
				(width 0.1524)
				(type default)
			)
			(layer "F.SilkS")
		)
		(fp_line
			(start 0.889 1.7018)
			(end -0.889 1.7018)
			(stroke
				(width 0.1524)
				(type default)
			)
			(layer "F.SilkS")
		)
		(fp_line
			(start -0.889 -1.7018)
			(end 0.889 -1.7018)
			(stroke
				(width 0.1524)
				(type default)
			)
			(layer "F.SilkS")
		)
		(fp_line
			(start 0.889 -1.7018)
			(end 0.889 1.7018)
			(stroke
				(width 0.1524)
				(type default)
			)
			(layer "F.SilkS")
		)
		(fp_rect
			(start -0.9652 1.778)
			(end 0.9652 -1.778)
			(stroke
				(width 0)
				(type default)
			)
			(fill no)
			(layer "F.CrtYd")
		)
		(fp_rect
			(start -0.9652 1.778)
			(end 0.9652 -1.778)
			(stroke
				(width 0)
				(type default)
			)
			(fill no)
			(layer "F.Fab")
		)
		(pad "1" smd rect
			(at 0 -0.9652 270)
			(size 1.397 1.143)
			(layers "F.Cu" "F.Mask" "F.Paste")
			(net "P0V9_E")
		)
		(pad "2" smd rect
			(at 0 0.9652 270)
			(size 1.397 1.143)
			(layers "F.Cu" "F.Mask" "F.Paste")
			(net "GB_VDDA")
		)
	)
	(footprint ""
		(layer "F.Cu")
		(at 199.39 -224.282)
		(property "Reference" "R1584"
			(at 0 0 0)
			(layer "F.SilkS")
			(hide yes)
			(effects
				(font
					(size 1.27 1.27)
				)
			)
		)
		(property "Value" "10KR2F-2-GP"
			(at 0.064008 -3.993896 0)
			(unlocked yes)
			(layer "F.Fab")
			(hide yes)
			(effects
				(font
					(size 1.016 1.016)
					(thickness 0.1524)
				)
			)
		)
		(property "Device Type" "R402H16"
			(at 0.064008 -5.517896 0)
			(unlocked yes)
			(layer "F.Fab")
			(hide yes)
			(effects
				(font
					(size 1.016 1.016)
					(thickness 0.1524)
				)
			)
		)
		(duplicate_pad_numbers_are_jumpers no)
		(fp_line
			(start -0.508 -0.9398)
			(end -0.508 0.9398)
			(stroke
				(width 0.1524)
				(type default)
			)
			(layer "F.SilkS")
		)
		(fp_line
			(start 0.508 -0.9398)
			(end -0.508 -0.9398)
			(stroke
				(width 0.1524)
				(type default)
			)
			(layer "F.SilkS")
		)
		(fp_rect
			(start -0.508 0.9398)
			(end 0.508 -0.9398)
			(stroke
				(width 0)
				(type default)
			)
			(fill no)
			(layer "F.CrtYd")
		)
		(fp_rect
			(start -0.508 0.9398)
			(end 0.508 -0.9398)
			(stroke
				(width 0)
				(type default)
			)
			(fill no)
			(layer "F.Fab")
		)
		(pad "1" smd custom
			(at 0 -0.4445)
			(size 0.1397 0.1397)
			(layers "F.Cu" "F.Mask" "F.Paste")
			(net "P3V3_STBY")
			(options
				(clearance outline)
				(anchor circle)
			)
			(primitives
				(gr_poly
					(pts
						(arc
							(start -0.1778 -0.2794)
							(mid -0.249642 -0.249642)
							(end -0.2794 -0.1778)
						)
						(arc
							(start -0.2794 0.1778)
							(mid -0.249642 0.249642)
							(end -0.1778 0.2794)
						)
						(arc
							(start 0.1778 0.2794)
							(mid 0.249642 0.249642)
							(end 0.2794 0.1778)
						)
						(arc
							(start 0.2794 -0.1778)
							(mid 0.249642 -0.249642)
							(end 0.1778 -0.2794)
						)
					)
					(width 0)
					(fill yes)
				)
			)
		)
		(pad "2" smd custom
			(at 0 0.4445)
			(size 0.1397 0.1397)
			(layers "F.Cu" "F.Mask" "F.Paste")
			(net "RSTBTN_FP_N")
			(options
				(clearance outline)
				(anchor circle)
			)
			(primitives
				(gr_poly
					(pts
						(arc
							(start -0.1778 -0.2794)
							(mid -0.249642 -0.249642)
							(end -0.2794 -0.1778)
						)
						(arc
							(start -0.2794 0.1778)
							(mid -0.249642 0.249642)
							(end -0.1778 0.2794)
						)
						(arc
							(start 0.1778 0.2794)
							(mid 0.249642 0.249642)
							(end 0.2794 0.1778)
						)
						(arc
							(start 0.2794 -0.1778)
							(mid 0.249642 -0.249642)
							(end 0.1778 -0.2794)
						)
					)
					(width 0)
					(fill yes)
				)
			)
		)
	)
	(footprint ""
		(layer "F.Cu")
		(at 90.424 -242.443 180)
		(property "Reference" "SR955"
			(at 0 0 180)
			(layer "F.SilkS")
			(hide yes)
			(effects
				(font
					(size 1.27 1.27)
				)
			)
		)
		(property "Value" "4K7R2F-GP"
			(at 0.064008 -3.993896 180)
			(unlocked yes)
			(layer "F.Fab")
			(hide yes)
			(effects
				(font
					(size 1.016 1.016)
					(thickness 0.1524)
				)
			)
		)
		(property "Device Type" "R402H16"
			(at 0.064008 -5.517896 180)
			(unlocked yes)
			(layer "F.Fab")
			(hide yes)
			(effects
				(font
					(size 1.016 1.016)
					(thickness 0.1524)
				)
			)
		)
		(duplicate_pad_numbers_are_jumpers no)
		(fp_line
			(start 0.508 -0.9398)
			(end -0.508 -0.9398)
			(stroke
				(width 0.1524)
				(type default)
			)
			(layer "F.SilkS")
		)
		(fp_line
			(start -0.508 -0.9398)
			(end -0.508 0.9398)
			(stroke
				(width 0.1524)
				(type default)
			)
			(layer "F.SilkS")
		)
		(fp_rect
			(start -0.508 0.9398)
			(end 0.508 -0.9398)
			(stroke
				(width 0)
				(type default)
			)
			(fill no)
			(layer "F.CrtYd")
		)
		(fp_rect
			(start -0.508 0.9398)
			(end 0.508 -0.9398)
			(stroke
				(width 0)
				(type default)
			)
			(fill no)
			(layer "F.Fab")
		)
		(pad "1" smd custom
			(at 0 -0.4445 180)
			(size 0.1397 0.1397)
			(layers "F.Cu" "F.Mask" "F.Paste")
			(net "SAS_FAULT_LED14")
			(options
				(clearance outline)
				(anchor circle)
			)
			(primitives
				(gr_poly
					(pts
						(arc
							(start -0.1778 -0.2794)
							(mid -0.249642 -0.249642)
							(end -0.2794 -0.1778)
						)
						(arc
							(start -0.2794 0.1778)
							(mid -0.249642 0.249642)
							(end -0.1778 0.2794)
						)
						(arc
							(start 0.1778 0.2794)
							(mid 0.249642 0.249642)
							(end 0.2794 0.1778)
						)
						(arc
							(start 0.2794 -0.1778)
							(mid 0.249642 -0.249642)
							(end 0.1778 -0.2794)
						)
					)
					(width 0)
					(fill yes)
				)
			)
		)
		(pad "2" smd custom
			(at 0 0.4445 180)
			(size 0.1397 0.1397)
			(layers "F.Cu" "F.Mask" "F.Paste")
			(net "P3V3_STBY")
			(options
				(clearance outline)
				(anchor circle)
			)
			(primitives
				(gr_poly
					(pts
						(arc
							(start -0.1778 -0.2794)
							(mid -0.249642 -0.249642)
							(end -0.2794 -0.1778)
						)
						(arc
							(start -0.2794 0.1778)
							(mid -0.249642 0.249642)
							(end -0.1778 0.2794)
						)
						(arc
							(start 0.1778 0.2794)
							(mid 0.249642 0.249642)
							(end 0.2794 0.1778)
						)
						(arc
							(start 0.2794 -0.1778)
							(mid 0.249642 -0.249642)
							(end 0.1778 -0.2794)
						)
					)
					(width 0)
					(fill yes)
				)
			)
		)
	)
	(footprint ""
		(layer "F.Cu")
		(at 303.149 -159.131)
		(property "Reference" "TP158"
			(at 0 0 0)
			(layer "F.SilkS")
			(hide yes)
			(effects
				(font
					(size 1.27 1.27)
				)
			)
		)
		(property "Value" "TPAD28"
			(at 0.0127 -1.8034 0)
			(unlocked yes)
			(layer "F.Fab")
			(hide yes)
			(effects
				(font
					(size 1.016 1.016)
					(thickness 0.1524)
				)
			)
		)
		(property "Device Type" "TPAD28"
			(at 0.0127 -3.3274 0)
			(unlocked yes)
			(layer "F.Fab")
			(hide yes)
			(effects
				(font
					(size 1.016 1.016)
					(thickness 0.1524)
				)
			)
		)
		(duplicate_pad_numbers_are_jumpers no)
		(fp_poly
			(pts
				(arc
					(start 0.3556 0)
					(mid -0.3556 0)
					(end 0.3556 0)
				)
			)
			(stroke
				(width 0)
				(type default)
			)
			(fill no)
			(layer "F.CrtYd")
		)
		(fp_poly
			(pts
				(arc
					(start 0.6096 0)
					(mid -0.6096 0)
					(end 0.6096 0)
				)
			)
			(stroke
				(width 0)
				(type default)
			)
			(fill no)
			(layer "F.Fab")
		)
		(pad "1" smd circle
			(at 0 0)
			(size 0.7112 0.7112)
			(layers "F.Cu" "F.Mask" "F.Paste")
			(net "TP_BMC_GPIOV3")
		)
	)
)
